# T6G (Grand Teton) — schematic netlist excerpt (pin names and nets, part order shuffled) for the footprints in the layout excerpt that follows; sources: Cadence DE-HDL packaged netlist, KiCad conversion of 04192023_DAF0TMB3IC0_F0TG_MB_C_brd_V02_OCP.brd

R2912  Q_RES  4.7K 5% EMPTY  pkg 0402LF  page 130 : A = P3V3_AUX ; B = FM_GPU_PWR_EN_R1
C6711  Q_CAP_DIFFBUS  DIFF BUS_0.22UF 6.3V 20% X6S  pkg C0201  page 341 : \1\ = P5E_CPU1_P2_TX_BUF_C_DP<9> ; \2\ = P5E_CPU1_P2_TX_BUF_DP<9>
R1378  Q_RES  10K 1% CHIP  pkg 0201LF  page 331 : A = RXDET_BYP_RT_CPU1_P1 ; B = GND

(kicad_pcb
	(version 20260206)
	(generator "pcbnew")
	(generator_version "10.0")
	(general
		(thickness 1.6)
		(legacy_teardrops no)
	)
	(paper "A4")
	(title_block
		(title "04192023_DAF0TMB3IC0_F0TG_MB_C_brd_V02_OCP.brd")
		(comment 1 "Grand Teton / footprints 3131-3133 of 8354")
	)
	(layers
		(0 "F.Cu" signal "TOP")
		(4 "In1.Cu" signal "GND")
		(6 "In2.Cu" signal "IN1")
		(8 "In3.Cu" signal "GND1")
		(10 "In4.Cu" signal "IN2")
		(12 "In5.Cu" signal "GND2")
		(14 "In6.Cu" signal "IN3")
		(16 "In7.Cu" signal "GND3")
		(18 "In8.Cu" signal "VCC")
		(20 "In9.Cu" signal "VCC1")
		(22 "In10.Cu" signal "GND4")
		(24 "In11.Cu" signal "IN4")
		(26 "In12.Cu" signal "GND5")
		(28 "In13.Cu" signal "IN5")
		(30 "In14.Cu" signal "GND6")
		(32 "In15.Cu" signal "IN6")
		(34 "In16.Cu" signal "GND7")
		(2 "B.Cu" signal "BOTTOM")
		(9 "F.Adhes" user "F.Adhesive")
		(11 "B.Adhes" user "B.Adhesive")
		(13 "F.Paste" user "Package Geometry/Pastemask Top")
		(15 "B.Paste" user "Package Geometry/Pastemask Bottom")
		(5 "F.SilkS" user "Ref Des/Silkscreen Top")
		(7 "B.SilkS" user "Ref Des/Silkscreen Bottom")
		(1 "F.Mask" user "Board Geometry/Soldermask Top")
		(3 "B.Mask" user "Board Geometry/Soldermask Bottom")
		(17 "Dwgs.User" user "User.Drawings")
		(19 "Cmts.User" user "User.Comments")
		(21 "Eco1.User" user "User.Eco1")
		(23 "Eco2.User" user "User.Eco2")
		(25 "Edge.Cuts" user "Board Geometry/Outline")
		(27 "Margin" user)
		(31 "F.CrtYd" user "Package Geometry/Place Bound Top")
		(29 "B.CrtYd" user "Package Geometry/Place Bound Bottom")
		(35 "F.Fab" user "Ref Des/Assembly Top")
		(33 "B.Fab" user "Ref Des/Assembly Bottom")
	)
	(footprint ""
		(layer "F.Cu")
		(at 104.7623 -389.49376)
		(property "Reference" "R1378"
			(at 0 0 0)
			(layer "F.SilkS")
			(hide yes)
			(effects
				(font
					(size 1.27 1.27)
				)
			)
		)
		(property "Value" ""
			(at 0 0 0)
			(layer "F.Fab")
			(effects
				(font
					(size 1.27 1.27)
				)
			)
		)
		(duplicate_pad_numbers_are_jumpers no)
		(fp_line
			(start -0.32512 -0.175006)
			(end 0.32512 -0.175006)
			(stroke
				(width 0.1)
				(type default)
			)
			(layer "F.Fab")
		)
		(fp_line
			(start -0.32512 0.175006)
			(end -0.32512 -0.175006)
			(stroke
				(width 0.1)
				(type default)
			)
			(layer "F.Fab")
		)
		(fp_line
			(start 0.32512 -0.175006)
			(end 0.32512 0.175006)
			(stroke
				(width 0.1)
				(type default)
			)
			(layer "F.Fab")
		)
		(fp_line
			(start 0.32512 0.175006)
			(end -0.32512 0.175006)
			(stroke
				(width 0.1)
				(type default)
			)
			(layer "F.Fab")
		)
		(pad "1" smd rect
			(at -0.2667 0)
			(size 0.3048 0.381)
			(layers "F.Cu" "F.Mask" "F.Paste")
			(net "RXDET_BYP_RT_CPU1_P1")
		)
		(pad "2" smd rect
			(at 0.2667 0 180)
			(size 0.3048 0.381)
			(layers "F.Cu" "F.Mask" "F.Paste")
			(net "GND")
		)
	)
	(footprint ""
		(layer "F.Cu")
		(at 143.352266 -408.517344 -90)
		(property "Reference" "C6711"
			(at 0 0 270)
			(layer "F.SilkS")
			(hide yes)
			(effects
				(font
					(size 1.27 1.27)
				)
			)
		)
		(property "Value" ""
			(at 0 0 270)
			(layer "F.Fab")
			(effects
				(font
					(size 1.27 1.27)
				)
			)
		)
		(duplicate_pad_numbers_are_jumpers no)
		(fp_line
			(start -0.299974 0.150114)
			(end -0.299974 -0.150114)
			(stroke
				(width 0.1)
				(type default)
			)
			(layer "F.Fab")
		)
		(fp_line
			(start 0.299974 0.150114)
			(end -0.299974 0.150114)
			(stroke
				(width 0.1)
				(type default)
			)
			(layer "F.Fab")
		)
		(fp_line
			(start -0.299974 -0.150114)
			(end 0.299974 -0.150114)
			(stroke
				(width 0.1)
				(type default)
			)
			(layer "F.Fab")
		)
		(fp_line
			(start 0.299974 -0.150114)
			(end 0.299974 0.150114)
			(stroke
				(width 0.1)
				(type default)
			)
			(layer "F.Fab")
		)
		(pad "1" smd rect
			(at -0.2667 0 270)
			(size 0.3048 0.381)
			(layers "F.Cu" "F.Mask" "F.Paste")
			(net "P5E_CPU1_P2_TX_BUF_C_DP<9>")
		)
		(pad "2" smd rect
			(at 0.2667 0 270)
			(size 0.3048 0.381)
			(layers "F.Cu" "F.Mask" "F.Paste")
			(net "P5E_CPU1_P2_TX_BUF_DP<9>")
		)
	)
	(footprint ""
		(layer "F.Cu")
		(at 47.18304 -438.753504 -90)
		(property "Reference" "R2912"
			(at 0 0 270)
			(layer "F.SilkS")
			(hide yes)
			(effects
				(font
					(size 1.27 1.27)
				)
			)
		)
		(property "Value" ""
			(at 0 0 270)
			(layer "F.Fab")
			(effects
				(font
					(size 1.27 1.27)
				)
			)
		)
		(duplicate_pad_numbers_are_jumpers no)
		(fp_line
			(start -0.7874 0.4064)
			(end -0.7874 -0.4064)
			(stroke
				(width 0.1524)
				(type default)
			)
			(layer "F.SilkS")
		)
		(fp_line
			(start 0.7874 0.4064)
			(end -0.7874 0.4064)
			(stroke
				(width 0.1524)
				(type default)
			)
			(layer "F.SilkS")
		)
		(fp_line
			(start -0.7874 -0.4064)
			(end 0.7874 -0.4064)
			(stroke
				(width 0.1524)
				(type default)
			)
			(layer "F.SilkS")
		)
		(fp_line
			(start 0.7874 -0.4064)
			(end 0.7874 0.4064)
			(stroke
				(width 0.1524)
				(type default)
			)
			(layer "F.SilkS")
		)
		(fp_line
			(start -0.67945 0.3048)
			(end -0.67945 -0.305054)
			(stroke
				(width 0.1)
				(type default)
			)
			(layer "F.Fab")
		)
		(fp_line
			(start -0.12065 0.3048)
			(end -0.67945 0.3048)
			(stroke
				(width 0.1)
				(type default)
			)
			(layer "F.Fab")
		)
		(fp_line
			(start 0.120396 0.3048)
			(end 0.120396 0.2794)
			(stroke
				(width 0.1)
				(type default)
			)
			(layer "F.Fab")
		)
		(fp_line
			(start 0.67945 0.3048)
			(end 0.120396 0.3048)
			(stroke
				(width 0.1)
				(type default)
			)
			(layer "F.Fab")
		)
		(fp_line
			(start -0.12065 0.2794)
			(end -0.12065 0.3048)
			(stroke
				(width 0.1)
				(type default)
			)
			(layer "F.Fab")
		)
		(fp_line
			(start 0.120396 0.2794)
			(end -0.12065 0.2794)
			(stroke
				(width 0.1)
				(type default)
			)
			(layer "F.Fab")
		)
		(fp_line
			(start -0.12065 -0.2794)
			(end 0.12065 -0.2794)
			(stroke
				(width 0.1)
				(type default)
			)
			(layer "F.Fab")
		)
		(fp_line
			(start 0.12065 -0.2794)
			(end 0.12065 -0.3048)
			(stroke
				(width 0.1)
				(type default)
			)
			(layer "F.Fab")
		)
		(fp_line
			(start 0.12065 -0.3048)
			(end 0.67945 -0.3048)
			(stroke
				(width 0.1)
				(type default)
			)
			(layer "F.Fab")
		)
		(fp_line
			(start 0.67945 -0.3048)
			(end 0.67945 0.3048)
			(stroke
				(width 0.1)
				(type default)
			)
			(layer "F.Fab")
		)
		(fp_line
			(start -0.67945 -0.305054)
			(end -0.12065 -0.305054)
			(stroke
				(width 0.1)
				(type default)
			)
			(layer "F.Fab")
		)
		(fp_line
			(start -0.12065 -0.305054)
			(end -0.12065 -0.2794)
			(stroke
				(width 0.1)
				(type default)
			)
			(layer "F.Fab")
		)
		(pad "1" smd circle
			(at -0.40005 0 270)
			(size 0 0)
			(layers "F.Cu" "F.Mask" "F.Paste")
			(net "P3V3_AUX")
		)
		(pad "2" smd circle
			(at 0.40005 0 270)
			(size 0 0)
			(layers "F.Cu" "F.Mask" "F.Paste")
			(net "FM_GPU_PWR_EN_R1")
		)
	)
)
